# T6G (Grand Teton) — schematic netlist excerpt (pin names and nets, part order shuffled) for the footprints in the layout excerpt that follows; sources: Cadence DE-HDL packaged netlist, KiCad conversion of 04192023_DAF0TMB3IC0_F0TG_MB_C_brd_V02_OCP.brd

U48  PI3CSW12ZUAEX  IC  pkg UQFN10_0-5_2X1-5  page 186
  \1d+\  = SMB_RT_CPU0_P1_ROM_MUX_1D_SCL
  \1d-\  = SMB_RT_CPU0_P1_ROM_MUX_1D_SDA
  \2d+\  = SMB_RT_CPU0_P1_ROM_MUX_2D_SCL
  \2d-\  = SMB_RT_CPU0_P1_ROM_MUX_2D_SDA
  GND  = GND
  \oe#\  = RT_ROM_MUX6_OE_N
  \d-\  = SMB_RT_CPU0_P1_ROM_R_SDA
  \d+\  = SMB_RT_CPU0_P1_ROM_R_SCL
  S  = FM_SMB_RT_ROM_MUX6_SEL
  VDD  = P3V3_AUX

PL53  Q_INDUCTOR  50NH/86A IND  pkg SMLF  page 194 : \1\ = SW_P12V_AUX_PVDDCR_CPU0_P0_FLT ; \2\ = P12V_AUX

(kicad_pcb
	(version 20260206)
	(generator "pcbnew")
	(generator_version "10.0")
	(general
		(thickness 1.6)
		(legacy_teardrops no)
	)
	(paper "A4")
	(title_block
		(title "04192023_DAF0TMB3IC0_F0TG_MB_C_brd_V02_OCP.brd")
		(comment 1 "Grand Teton / footprints 3880-3881 of 8354")
	)
	(layers
		(0 "F.Cu" signal "TOP")
		(4 "In1.Cu" signal "GND")
		(6 "In2.Cu" signal "IN1")
		(8 "In3.Cu" signal "GND1")
		(10 "In4.Cu" signal "IN2")
		(12 "In5.Cu" signal "GND2")
		(14 "In6.Cu" signal "IN3")
		(16 "In7.Cu" signal "GND3")
		(18 "In8.Cu" signal "VCC")
		(20 "In9.Cu" signal "VCC1")
		(22 "In10.Cu" signal "GND4")
		(24 "In11.Cu" signal "IN4")
		(26 "In12.Cu" signal "GND5")
		(28 "In13.Cu" signal "IN5")
		(30 "In14.Cu" signal "GND6")
		(32 "In15.Cu" signal "IN6")
		(34 "In16.Cu" signal "GND7")
		(2 "B.Cu" signal "BOTTOM")
		(9 "F.Adhes" user "F.Adhesive")
		(11 "B.Adhes" user "B.Adhesive")
		(13 "F.Paste" user "Package Geometry/Pastemask Top")
		(15 "B.Paste" user "Package Geometry/Pastemask Bottom")
		(5 "F.SilkS" user "Ref Des/Silkscreen Top")
		(7 "B.SilkS" user "Ref Des/Silkscreen Bottom")
		(1 "F.Mask" user "Board Geometry/Soldermask Top")
		(3 "B.Mask" user "Board Geometry/Soldermask Bottom")
		(17 "Dwgs.User" user "User.Drawings")
		(19 "Cmts.User" user "User.Comments")
		(21 "Eco1.User" user "User.Eco1")
		(23 "Eco2.User" user "User.Eco2")
		(25 "Edge.Cuts" user "Board Geometry/Outline")
		(27 "Margin" user)
		(31 "F.CrtYd" user "Package Geometry/Place Bound Top")
		(29 "B.CrtYd" user "Package Geometry/Place Bound Bottom")
		(35 "F.Fab" user "Ref Des/Assembly Top")
		(33 "B.Fab" user "Ref Des/Assembly Bottom")
	)
	(footprint ""
		(layer "F.Cu")
		(at 290.890198 -395.231366 90)
		(property "Reference" "U48"
			(at 0.91948 3.869182 90)
			(unlocked yes)
			(layer "F.SilkS")
			(effects
				(font
					(size 0.7874 0.5842)
					(thickness 0.1524)
				)
			)
		)
		(property "Value" ""
			(at 0 0 90)
			(layer "F.Fab")
			(effects
				(font
					(size 1.27 1.27)
				)
			)
		)
		(duplicate_pad_numbers_are_jumpers no)
		(fp_line
			(start 1.03378 -1.284478)
			(end 1.03378 1.284478)
			(stroke
				(width 0.1524)
				(type default)
			)
			(layer "F.SilkS")
		)
		(fp_line
			(start -1.03378 -1.284478)
			(end 1.03378 -1.284478)
			(stroke
				(width 0.1524)
				(type default)
			)
			(layer "F.SilkS")
		)
		(fp_line
			(start 1.03378 1.284478)
			(end -1.03378 1.284478)
			(stroke
				(width 0.1524)
				(type default)
			)
			(layer "F.SilkS")
		)
		(fp_line
			(start -1.03378 1.284478)
			(end -1.03378 -1.284478)
			(stroke
				(width 0.1524)
				(type default)
			)
			(layer "F.SilkS")
		)
		(fp_poly
			(pts
				(xy -1.23952 -1.219454) (xy -1.894586 -1.387602) (xy -1.498092 -1.844548)
			)
			(stroke
				(width 0)
				(type default)
			)
			(fill yes)
			(layer "F.SilkS")
		)
		(fp_line
			(start 0.774954 -1.02489)
			(end 0.774954 1.02489)
			(stroke
				(width 0.1)
				(type default)
			)
			(layer "F.Fab")
		)
		(fp_line
			(start -0.774954 -1.02489)
			(end 0.774954 -1.02489)
			(stroke
				(width 0.1)
				(type default)
			)
			(layer "F.Fab")
		)
		(fp_line
			(start 0.774954 1.02489)
			(end -0.774954 1.02489)
			(stroke
				(width 0.1)
				(type default)
			)
			(layer "F.Fab")
		)
		(fp_line
			(start -0.774954 1.02489)
			(end -0.774954 -1.02489)
			(stroke
				(width 0.1)
				(type default)
			)
			(layer "F.Fab")
		)
		(fp_poly
			(pts
				(xy -1.201674 -0.750062) (xy -1.806702 -0.447548) (xy -1.806702 -1.052576)
			)
			(stroke
				(width 0)
				(type default)
			)
			(fill yes)
			(layer "F.Fab")
		)
		(pad "1" smd rect
			(at -0.64008 -0.750062 180)
			(size 0.3048 0.5334)
			(layers "F.Cu" "F.Mask" "F.Paste")
			(net "SMB_RT_CPU0_P1_ROM_MUX_1D_SCL")
		)
		(pad "2" smd rect
			(at -0.64008 -0.249936 180)
			(size 0.254 0.5334)
			(layers "F.Cu" "F.Mask" "F.Paste")
			(net "SMB_RT_CPU0_P1_ROM_MUX_1D_SDA")
		)
		(pad "3" smd rect
			(at -0.64008 0.249936 180)
			(size 0.254 0.5334)
			(layers "F.Cu" "F.Mask" "F.Paste")
			(net "SMB_RT_CPU0_P1_ROM_MUX_2D_SCL")
		)
		(pad "4" smd rect
			(at -0.64008 0.750062 180)
			(size 0.3048 0.5334)
			(layers "F.Cu" "F.Mask" "F.Paste")
			(net "SMB_RT_CPU0_P1_ROM_MUX_2D_SDA")
		)
		(pad "5" smd rect
			(at 0 0.839978 90)
			(size 0.3302 0.635)
			(layers "F.Cu" "F.Mask" "F.Paste")
			(net "GND")
		)
		(pad "6" smd rect
			(at 0.64008 0.750062 180)
			(size 0.3048 0.5334)
			(layers "F.Cu" "F.Mask" "F.Paste")
			(net "RT_ROM_MUX6_OE_N")
		)
		(pad "7" smd rect
			(at 0.64008 0.249936 180)
			(size 0.254 0.5334)
			(layers "F.Cu" "F.Mask" "F.Paste")
			(net "SMB_RT_CPU0_P1_ROM_R_SDA")
		)
		(pad "8" smd rect
			(at 0.64008 -0.249936 180)
			(size 0.254 0.5334)
			(layers "F.Cu" "F.Mask" "F.Paste")
			(net "SMB_RT_CPU0_P1_ROM_R_SCL")
		)
		(pad "9" smd rect
			(at 0.64008 -0.750062 180)
			(size 0.3048 0.5334)
			(layers "F.Cu" "F.Mask" "F.Paste")
			(net "FM_SMB_RT_ROM_MUX6_SEL")
		)
		(pad "10" smd rect
			(at 0 -0.839978 90)
			(size 0.3302 0.635)
			(layers "F.Cu" "F.Mask" "F.Paste")
			(net "P3V3_AUX")
		)
	)
	(footprint ""
		(layer "F.Cu")
		(at 369.330478 -159.907732 -90)
		(property "Reference" "PL53"
			(at -0.072136 3.778504 90)
			(unlocked yes)
			(layer "F.SilkS")
			(effects
				(font
					(size 0.7874 0.5842)
					(thickness 0.1524)
				)
				(justify left)
			)
		)
		(property "Value" ""
			(at 0 0 270)
			(layer "F.Fab")
			(effects
				(font
					(size 1.27 1.27)
				)
			)
		)
		(duplicate_pad_numbers_are_jumpers no)
		(fp_line
			(start -3.050032 2.999994)
			(end 3.050032 2.999994)
			(stroke
				(width 0.1524)
				(type default)
			)
			(layer "F.SilkS")
		)
		(fp_line
			(start 3.050032 2.999994)
			(end 3.050032 1.4478)
			(stroke
				(width 0.1524)
				(type default)
			)
			(layer "F.SilkS")
		)
		(fp_line
			(start -3.050032 1.4478)
			(end -3.050032 2.999994)
			(stroke
				(width 0.1524)
				(type default)
			)
			(layer "F.SilkS")
		)
		(fp_line
			(start 3.050032 -1.4478)
			(end 3.050032 -2.999994)
			(stroke
				(width 0.1524)
				(type default)
			)
			(layer "F.SilkS")
		)
		(fp_line
			(start -3.050032 -2.999994)
			(end -3.050032 -1.4478)
			(stroke
				(width 0.1524)
				(type default)
			)
			(layer "F.SilkS")
		)
		(fp_line
			(start 3.050032 -2.999994)
			(end -3.050032 -2.999994)
			(stroke
				(width 0.1524)
				(type default)
			)
			(layer "F.SilkS")
		)
		(fp_line
			(start -3.050032 2.999994)
			(end 3.050032 2.999994)
			(stroke
				(width 0.1)
				(type default)
			)
			(layer "F.Fab")
		)
		(fp_line
			(start 3.050032 2.999994)
			(end 3.050032 -2.999994)
			(stroke
				(width 0.1)
				(type default)
			)
			(layer "F.Fab")
		)
		(fp_line
			(start -3.050032 -2.999994)
			(end -3.050032 2.999994)
			(stroke
				(width 0.1)
				(type default)
			)
			(layer "F.Fab")
		)
		(fp_line
			(start 3.050032 -2.999994)
			(end -3.050032 -2.999994)
			(stroke
				(width 0.1)
				(type default)
			)
			(layer "F.Fab")
		)
		(pad "1" smd rect
			(at -2.525014 0 270)
			(size 1.651 2.6162)
			(layers "F.Cu" "F.Mask" "F.Paste")
			(net "SW_P12V_AUX_PVDDCR_CPU0_P0_FLT")
		)
		(pad "2" smd rect
			(at 2.525014 0 270)
			(size 1.651 2.6162)
			(layers "F.Cu" "F.Mask" "F.Paste")
			(net "P12V_AUX")
		)
	)
)
